(kicad_pcb
	(version 20260206)
	(generator "pcbnew")
	(generator_version "10.0")
	(general
		(thickness 1.6)
		(legacy_teardrops no)
	)
	(paper "A4")
	(title_block
		(title "01162023_DA0F0TEBIF0_F0T_Expander_BD_F_brd_V02_OCP.brd")
		(comment 1 "Grand Teton / footprints 5125-5129 of 9728")
	)
	(layers
		(0 "F.Cu" signal "TOP")
		(4 "In1.Cu" signal "GND")
		(6 "In2.Cu" signal "VCC")
		(8 "In3.Cu" signal "VCC1")
		(10 "In4.Cu" signal "GND1")
		(12 "In5.Cu" signal "IN1")
		(14 "In6.Cu" signal "GND2")
		(16 "In7.Cu" signal "IN2")
		(18 "In8.Cu" signal "GND3")
		(20 "In9.Cu" signal "IN3")
		(22 "In10.Cu" signal "GND4")
		(24 "In11.Cu" signal "IN4")
		(26 "In12.Cu" signal "GND5")
		(28 "In13.Cu" signal "IN5")
		(30 "In14.Cu" signal "GND6")
		(32 "In15.Cu" signal "IN6")
		(34 "In16.Cu" signal "GND7")
		(2 "B.Cu" signal "BOTTOM")
		(9 "F.Adhes" user "F.Adhesive")
		(11 "B.Adhes" user "B.Adhesive")
		(13 "F.Paste" user "Package Geometry/Pastemask Top")
		(15 "B.Paste" user "Package Geometry/Pastemask Bottom")
		(5 "F.SilkS" user "Ref Des/Silkscreen Top")
		(7 "B.SilkS" user "Ref Des/Silkscreen Bottom")
		(1 "F.Mask" user "Board Geometry/Soldermask Top")
		(3 "B.Mask" user "Board Geometry/Soldermask Bottom")
		(17 "Dwgs.User" user "User.Drawings")
		(19 "Cmts.User" user "User.Comments")
		(21 "Eco1.User" user "User.Eco1")
		(23 "Eco2.User" user "User.Eco2")
		(25 "Edge.Cuts" user "Board Geometry/Outline")
		(27 "Margin" user)
		(31 "F.CrtYd" user "Package Geometry/Place Bound Top")
		(29 "B.CrtYd" user "Package Geometry/Place Bound Bottom")
		(35 "F.Fab" user "Ref Des/Assembly Top")
		(33 "B.Fab" user "Ref Des/Assembly Bottom")
	)
	(footprint ""
		(layer "F.Cu")
		(at 179.667154 -171.675806)
		(property "Reference" "R151"
			(at 0 0 0)
			(layer "F.SilkS")
			(hide yes)
			(effects
				(font
					(size 1.27 1.27)
				)
			)
		)
		(property "Value" ""
			(at 0 0 0)
			(layer "F.Fab")
			(effects
				(font
					(size 1.27 1.27)
				)
			)
		)
		(duplicate_pad_numbers_are_jumpers no)
		(fp_line
			(start -0.7874 -0.4064)
			(end 0.7874 -0.4064)
			(stroke
				(width 0.1524)
				(type default)
			)
			(layer "F.SilkS")
		)
		(fp_line
			(start -0.7874 0.4064)
			(end -0.7874 -0.4064)
			(stroke
				(width 0.1524)
				(type default)
			)
			(layer "F.SilkS")
		)
		(fp_line
			(start 0.7874 -0.4064)
			(end 0.7874 0.4064)
			(stroke
				(width 0.1524)
				(type default)
			)
			(layer "F.SilkS")
		)
		(fp_line
			(start 0.7874 0.4064)
			(end -0.7874 0.4064)
			(stroke
				(width 0.1524)
				(type default)
			)
			(layer "F.SilkS")
		)
		(fp_line
			(start -0.67945 -0.305054)
			(end -0.12065 -0.305054)
			(stroke
				(width 0.1)
				(type default)
			)
			(layer "F.Fab")
		)
		(fp_line
			(start -0.67945 0.3048)
			(end -0.67945 -0.305054)
			(stroke
				(width 0.1)
				(type default)
			)
			(layer "F.Fab")
		)
		(fp_line
			(start -0.12065 -0.305054)
			(end -0.12065 -0.2794)
			(stroke
				(width 0.1)
				(type default)
			)
			(layer "F.Fab")
		)
		(fp_line
			(start -0.12065 -0.2794)
			(end 0.12065 -0.2794)
			(stroke
				(width 0.1)
				(type default)
			)
			(layer "F.Fab")
		)
		(fp_line
			(start -0.12065 0.2794)
			(end -0.12065 0.3048)
			(stroke
				(width 0.1)
				(type default)
			)
			(layer "F.Fab")
		)
		(fp_line
			(start -0.12065 0.3048)
			(end -0.67945 0.3048)
			(stroke
				(width 0.1)
				(type default)
			)
			(layer "F.Fab")
		)
		(fp_line
			(start 0.120396 0.2794)
			(end -0.12065 0.2794)
			(stroke
				(width 0.1)
				(type default)
			)
			(layer "F.Fab")
		)
		(fp_line
			(start 0.120396 0.3048)
			(end 0.120396 0.2794)
			(stroke
				(width 0.1)
				(type default)
			)
			(layer "F.Fab")
		)
		(fp_line
			(start 0.12065 -0.3048)
			(end 0.67945 -0.3048)
			(stroke
				(width 0.1)
				(type default)
			)
			(layer "F.Fab")
		)
		(fp_line
			(start 0.12065 -0.2794)
			(end 0.12065 -0.3048)
			(stroke
				(width 0.1)
				(type default)
			)
			(layer "F.Fab")
		)
		(fp_line
			(start 0.67945 -0.3048)
			(end 0.67945 0.3048)
			(stroke
				(width 0.1)
				(type default)
			)
			(layer "F.Fab")
		)
		(fp_line
			(start 0.67945 0.3048)
			(end 0.120396 0.3048)
			(stroke
				(width 0.1)
				(type default)
			)
			(layer "F.Fab")
		)
		(pad "1" smd circle
			(at -0.40005 0)
			(size 0 0)
			(layers "F.Cu" "F.Mask" "F.Paste")
			(net "P3V3_NIC2")
		)
		(pad "2" smd circle
			(at 0.40005 0)
			(size 0 0)
			(layers "F.Cu" "F.Mask" "F.Paste")
			(net "HP_NIC2_PWRGD")
		)
	)
	(footprint ""
		(layer "F.Cu")
		(at 435.104032 -289.230816 90)
		(property "Reference" "R4003"
			(at 0 0 90)
			(layer "F.SilkS")
			(hide yes)
			(effects
				(font
					(size 1.27 1.27)
				)
			)
		)
		(property "Value" ""
			(at 0 0 90)
			(layer "F.Fab")
			(effects
				(font
					(size 1.27 1.27)
				)
			)
		)
		(duplicate_pad_numbers_are_jumpers no)
		(fp_line
			(start 0.7874 -0.4064)
			(end 0.7874 0.4064)
			(stroke
				(width 0.1524)
				(type default)
			)
			(layer "F.SilkS")
		)
		(fp_line
			(start -0.7874 -0.4064)
			(end 0.7874 -0.4064)
			(stroke
				(width 0.1524)
				(type default)
			)
			(layer "F.SilkS")
		)
		(fp_line
			(start 0.7874 0.4064)
			(end -0.7874 0.4064)
			(stroke
				(width 0.1524)
				(type default)
			)
			(layer "F.SilkS")
		)
		(fp_line
			(start -0.7874 0.4064)
			(end -0.7874 -0.4064)
			(stroke
				(width 0.1524)
				(type default)
			)
			(layer "F.SilkS")
		)
		(fp_line
			(start -0.12065 -0.305054)
			(end -0.12065 -0.2794)
			(stroke
				(width 0.1)
				(type default)
			)
			(layer "F.Fab")
		)
		(fp_line
			(start -0.67945 -0.305054)
			(end -0.12065 -0.305054)
			(stroke
				(width 0.1)
				(type default)
			)
			(layer "F.Fab")
		)
		(fp_line
			(start 0.67945 -0.3048)
			(end 0.67945 0.3048)
			(stroke
				(width 0.1)
				(type default)
			)
			(layer "F.Fab")
		)
		(fp_line
			(start 0.12065 -0.3048)
			(end 0.67945 -0.3048)
			(stroke
				(width 0.1)
				(type default)
			)
			(layer "F.Fab")
		)
		(fp_line
			(start 0.12065 -0.2794)
			(end 0.12065 -0.3048)
			(stroke
				(width 0.1)
				(type default)
			)
			(layer "F.Fab")
		)
		(fp_line
			(start -0.12065 -0.2794)
			(end 0.12065 -0.2794)
			(stroke
				(width 0.1)
				(type default)
			)
			(layer "F.Fab")
		)
		(fp_line
			(start 0.120396 0.2794)
			(end -0.12065 0.2794)
			(stroke
				(width 0.1)
				(type default)
			)
			(layer "F.Fab")
		)
		(fp_line
			(start -0.12065 0.2794)
			(end -0.12065 0.3048)
			(stroke
				(width 0.1)
				(type default)
			)
			(layer "F.Fab")
		)
		(fp_line
			(start 0.67945 0.3048)
			(end 0.120396 0.3048)
			(stroke
				(width 0.1)
				(type default)
			)
			(layer "F.Fab")
		)
		(fp_line
			(start 0.120396 0.3048)
			(end 0.120396 0.2794)
			(stroke
				(width 0.1)
				(type default)
			)
			(layer "F.Fab")
		)
		(fp_line
			(start -0.12065 0.3048)
			(end -0.67945 0.3048)
			(stroke
				(width 0.1)
				(type default)
			)
			(layer "F.Fab")
		)
		(fp_line
			(start -0.67945 0.3048)
			(end -0.67945 -0.305054)
			(stroke
				(width 0.1)
				(type default)
			)
			(layer "F.Fab")
		)
		(pad "1" smd circle
			(at -0.40005 0 90)
			(size 0 0)
			(layers "F.Cu" "F.Mask" "F.Paste")
			(net "PWRGD_P1V8_PEX_R")
		)
		(pad "2" smd circle
			(at 0.40005 0 90)
			(size 0 0)
			(layers "F.Cu" "F.Mask" "F.Paste")
			(net "PWRGD_P1V8_PEX3_R")
		)
	)
	(footprint ""
		(layer "F.Cu")
		(at 161.571686 -25.342342 -90)
		(property "Reference" "R424"
			(at 0 0 270)
			(layer "F.SilkS")
			(hide yes)
			(effects
				(font
					(size 1.27 1.27)
				)
			)
		)
		(property "Value" ""
			(at 0 0 270)
			(layer "F.Fab")
			(effects
				(font
					(size 1.27 1.27)
				)
			)
		)
		(duplicate_pad_numbers_are_jumpers no)
		(fp_line
			(start -0.7874 0.4064)
			(end -0.7874 -0.4064)
			(stroke
				(width 0.1524)
				(type default)
			)
			(layer "F.SilkS")
		)
		(fp_line
			(start 0.7874 0.4064)
			(end -0.7874 0.4064)
			(stroke
				(width 0.1524)
				(type default)
			)
			(layer "F.SilkS")
		)
		(fp_line
			(start -0.7874 -0.4064)
			(end 0.7874 -0.4064)
			(stroke
				(width 0.1524)
				(type default)
			)
			(layer "F.SilkS")
		)
		(fp_line
			(start 0.7874 -0.4064)
			(end 0.7874 0.4064)
			(stroke
				(width 0.1524)
				(type default)
			)
			(layer "F.SilkS")
		)
		(fp_line
			(start -0.67945 0.3048)
			(end -0.67945 -0.305054)
			(stroke
				(width 0.1)
				(type default)
			)
			(layer "F.Fab")
		)
		(fp_line
			(start -0.12065 0.3048)
			(end -0.67945 0.3048)
			(stroke
				(width 0.1)
				(type default)
			)
			(layer "F.Fab")
		)
		(fp_line
			(start 0.120396 0.3048)
			(end 0.120396 0.2794)
			(stroke
				(width 0.1)
				(type default)
			)
			(layer "F.Fab")
		)
		(fp_line
			(start 0.67945 0.3048)
			(end 0.120396 0.3048)
			(stroke
				(width 0.1)
				(type default)
			)
			(layer "F.Fab")
		)
		(fp_line
			(start -0.12065 0.2794)
			(end -0.12065 0.3048)
			(stroke
				(width 0.1)
				(type default)
			)
			(layer "F.Fab")
		)
		(fp_line
			(start 0.120396 0.2794)
			(end -0.12065 0.2794)
			(stroke
				(width 0.1)
				(type default)
			)
			(layer "F.Fab")
		)
		(fp_line
			(start -0.12065 -0.2794)
			(end 0.12065 -0.2794)
			(stroke
				(width 0.1)
				(type default)
			)
			(layer "F.Fab")
		)
		(fp_line
			(start 0.12065 -0.2794)
			(end 0.12065 -0.3048)
			(stroke
				(width 0.1)
				(type default)
			)
			(layer "F.Fab")
		)
		(fp_line
			(start 0.12065 -0.3048)
			(end 0.67945 -0.3048)
			(stroke
				(width 0.1)
				(type default)
			)
			(layer "F.Fab")
		)
		(fp_line
			(start 0.67945 -0.3048)
			(end 0.67945 0.3048)
			(stroke
				(width 0.1)
				(type default)
			)
			(layer "F.Fab")
		)
		(fp_line
			(start -0.67945 -0.305054)
			(end -0.12065 -0.305054)
			(stroke
				(width 0.1)
				(type default)
			)
			(layer "F.Fab")
		)
		(fp_line
			(start -0.12065 -0.305054)
			(end -0.12065 -0.2794)
			(stroke
				(width 0.1)
				(type default)
			)
			(layer "F.Fab")
		)
		(pad "1" smd circle
			(at -0.40005 0 270)
			(size 0 0)
			(layers "F.Cu" "F.Mask" "F.Paste")
			(net "P3V3_SSD5")
		)
		(pad "2" smd circle
			(at 0.40005 0 270)
			(size 0 0)
			(layers "F.Cu" "F.Mask" "F.Paste")
			(net "DUALPORT_N_SSD5")
		)
	)
	(footprint ""
		(layer "F.Cu")
		(at 323.255386 -96.811592 -90)
		(property "Reference" "R740"
			(at 0 0 270)
			(layer "F.SilkS")
			(hide yes)
			(effects
				(font
					(size 1.27 1.27)
				)
			)
		)
		(property "Value" ""
			(at 0 0 270)
			(layer "F.Fab")
			(effects
				(font
					(size 1.27 1.27)
				)
			)
		)
		(duplicate_pad_numbers_are_jumpers no)
		(fp_line
			(start -0.7874 0.4064)
			(end -0.7874 -0.4064)
			(stroke
				(width 0.1524)
				(type default)
			)
			(layer "F.SilkS")
		)
		(fp_line
			(start 0.7874 0.4064)
			(end -0.7874 0.4064)
			(stroke
				(width 0.1524)
				(type default)
			)
			(layer "F.SilkS")
		)
		(fp_line
			(start -0.7874 -0.4064)
			(end 0.7874 -0.4064)
			(stroke
				(width 0.1524)
				(type default)
			)
			(layer "F.SilkS")
		)
		(fp_line
			(start 0.7874 -0.4064)
			(end 0.7874 0.4064)
			(stroke
				(width 0.1524)
				(type default)
			)
			(layer "F.SilkS")
		)
		(fp_line
			(start -0.67945 0.3048)
			(end -0.67945 -0.305054)
			(stroke
				(width 0.1)
				(type default)
			)
			(layer "F.Fab")
		)
		(fp_line
			(start -0.12065 0.3048)
			(end -0.67945 0.3048)
			(stroke
				(width 0.1)
				(type default)
			)
			(layer "F.Fab")
		)
		(fp_line
			(start 0.120396 0.3048)
			(end 0.120396 0.2794)
			(stroke
				(width 0.1)
				(type default)
			)
			(layer "F.Fab")
		)
		(fp_line
			(start 0.67945 0.3048)
			(end 0.120396 0.3048)
			(stroke
				(width 0.1)
				(type default)
			)
			(layer "F.Fab")
		)
		(fp_line
			(start -0.12065 0.2794)
			(end -0.12065 0.3048)
			(stroke
				(width 0.1)
				(type default)
			)
			(layer "F.Fab")
		)
		(fp_line
			(start 0.120396 0.2794)
			(end -0.12065 0.2794)
			(stroke
				(width 0.1)
				(type default)
			)
			(layer "F.Fab")
		)
		(fp_line
			(start -0.12065 -0.2794)
			(end 0.12065 -0.2794)
			(stroke
				(width 0.1)
				(type default)
			)
			(layer "F.Fab")
		)
		(fp_line
			(start 0.12065 -0.2794)
			(end 0.12065 -0.3048)
			(stroke
				(width 0.1)
				(type default)
			)
			(layer "F.Fab")
		)
		(fp_line
			(start 0.12065 -0.3048)
			(end 0.67945 -0.3048)
			(stroke
				(width 0.1)
				(type default)
			)
			(layer "F.Fab")
		)
		(fp_line
			(start 0.67945 -0.3048)
			(end 0.67945 0.3048)
			(stroke
				(width 0.1)
				(type default)
			)
			(layer "F.Fab")
		)
		(fp_line
			(start -0.67945 -0.305054)
			(end -0.12065 -0.305054)
			(stroke
				(width 0.1)
				(type default)
			)
			(layer "F.Fab")
		)
		(fp_line
			(start -0.12065 -0.305054)
			(end -0.12065 -0.2794)
			(stroke
				(width 0.1)
				(type default)
			)
			(layer "F.Fab")
		)
		(pad "1" smd circle
			(at -0.40005 0 270)
			(size 0 0)
			(layers "F.Cu" "F.Mask" "F.Paste")
			(net "NIC5_ADC_ALERT_N")
		)
		(pad "2" smd circle
			(at 0.40005 0 270)
			(size 0 0)
			(layers "F.Cu" "F.Mask" "F.Paste")
			(net "NIC_ADC_ALERT_N")
		)
	)
	(footprint ""
		(layer "F.Cu")
		(at 211.506816 -365.975646)
		(property "Reference" "PR7"
			(at 0 0 0)
			(layer "F.SilkS")
			(hide yes)
			(effects
				(font
					(size 1.27 1.27)
				)
			)
		)
		(property "Value" ""
			(at 0 0 0)
			(layer "F.Fab")
			(effects
				(font
					(size 1.27 1.27)
				)
			)
		)
		(duplicate_pad_numbers_are_jumpers no)
		(fp_line
			(start -0.7874 -0.4064)
			(end 0.7874 -0.4064)
			(stroke
				(width 0.1524)
				(type default)
			)
			(layer "F.SilkS")
		)
		(fp_line
			(start -0.7874 0.4064)
			(end -0.7874 -0.4064)
			(stroke
				(width 0.1524)
				(type default)
			)
			(layer "F.SilkS")
		)
		(fp_line
			(start 0.7874 -0.4064)
			(end 0.7874 0.4064)
			(stroke
				(width 0.1524)
				(type default)
			)
			(layer "F.SilkS")
		)
		(fp_line
			(start 0.7874 0.4064)
			(end -0.7874 0.4064)
			(stroke
				(width 0.1524)
				(type default)
			)
			(layer "F.SilkS")
		)
		(fp_line
			(start -0.67945 -0.305054)
			(end -0.12065 -0.305054)
			(stroke
				(width 0.1)
				(type default)
			)
			(layer "F.Fab")
		)
		(fp_line
			(start -0.67945 0.3048)
			(end -0.67945 -0.305054)
			(stroke
				(width 0.1)
				(type default)
			)
			(layer "F.Fab")
		)
		(fp_line
			(start -0.12065 -0.305054)
			(end -0.12065 -0.2794)
			(stroke
				(width 0.1)
				(type default)
			)
			(layer "F.Fab")
		)
		(fp_line
			(start -0.12065 -0.2794)
			(end 0.12065 -0.2794)
			(stroke
				(width 0.1)
				(type default)
			)
			(layer "F.Fab")
		)
		(fp_line
			(start -0.12065 0.2794)
			(end -0.12065 0.3048)
			(stroke
				(width 0.1)
				(type default)
			)
			(layer "F.Fab")
		)
		(fp_line
			(start -0.12065 0.3048)
			(end -0.67945 0.3048)
			(stroke
				(width 0.1)
				(type default)
			)
			(layer "F.Fab")
		)
		(fp_line
			(start 0.120396 0.2794)
			(end -0.12065 0.2794)
			(stroke
				(width 0.1)
				(type default)
			)
			(layer "F.Fab")
		)
		(fp_line
			(start 0.120396 0.3048)
			(end 0.120396 0.2794)
			(stroke
				(width 0.1)
				(type default)
			)
			(layer "F.Fab")
		)
		(fp_line
			(start 0.12065 -0.3048)
			(end 0.67945 -0.3048)
			(stroke
				(width 0.1)
				(type default)
			)
			(layer "F.Fab")
		)
		(fp_line
			(start 0.12065 -0.2794)
			(end 0.12065 -0.3048)
			(stroke
				(width 0.1)
				(type default)
			)
			(layer "F.Fab")
		)
		(fp_line
			(start 0.67945 -0.3048)
			(end 0.67945 0.3048)
			(stroke
				(width 0.1)
				(type default)
			)
			(layer "F.Fab")
		)
		(fp_line
			(start 0.67945 0.3048)
			(end 0.120396 0.3048)
			(stroke
				(width 0.1)
				(type default)
			)
			(layer "F.Fab")
		)
		(pad "1" smd circle
			(at -0.40005 0)
			(size 0 0)
			(layers "F.Cu" "F.Mask" "F.Paste")
			(net "HSC_D_OC")
		)
		(pad "2" smd circle
			(at 0.40005 0)
			(size 0 0)
			(layers "F.Cu" "F.Mask" "F.Paste")
			(net "HSC_VDD")
		)
	)
)
